(kicad_sch
	(version 20250114)
	(generator "eeschema")
	(generator_version "9.0")
	(paper "A3")
	(title_block
		(title "OCuLink to 10GbE adapter")
		(date "2026-02-23")
		(rev "1.1.0")
		(company "Antmicro Ltd")
		(comment 1 "www.antmicro.com")
	)
	(text "Flash Memory"
		(exclude_from_sim no)
		(at 213.36 111.76 0)
		(effects
			(font
				(size 2.54 2.54)
				(thickness 0.508)
				(bold yes)
			)
		)
	)
	(junction
		(at 196.85 133.35)
		(diameter 0)
		(color 0 0 0 0)
	)
	(junction
		(at 224.79 156.21)
		(diameter 0)
		(color 0 0 0 0)
	)
	(junction
		(at 224.79 133.35)
		(diameter 0)
		(color 0 0 0 0)
	)
	(junction
		(at 195.58 193.04)
		(diameter 0)
		(color 0 0 0 0)
	)
	(junction
		(at 209.55 133.35)
		(diameter 0)
		(color 0 0 0 0)
	)
	(junction
		(at 224.79 143.51)
		(diameter 0)
		(color 0 0 0 0)
	)
	(no_connect
		(at 229.87 182.88)
	)
	(bus_entry
		(at 171.45 156.21)
		(size 2.54 -2.54)
		(stroke
			(width 0)
			(type default)
		)
	)
	(bus_entry
		(at 171.45 158.75)
		(size 2.54 -2.54)
		(stroke
			(width 0)
			(type default)
		)
	)
	(bus_entry
		(at 171.45 148.59)
		(size 2.54 -2.54)
		(stroke
			(width 0)
			(type default)
		)
	)
	(bus_entry
		(at 171.45 146.05)
		(size 2.54 -2.54)
		(stroke
			(width 0)
			(type default)
		)
	)
	(wire
		(pts
			(xy 196.85 140.97) (xy 196.85 148.59)
		)
		(stroke
			(width 0)
			(type default)
		)
	)
	(wire
		(pts
			(xy 209.55 130.81) (xy 209.55 133.35)
		)
		(stroke
			(width 0)
			(type default)
		)
	)
	(wire
		(pts
			(xy 173.99 153.67) (xy 203.2 153.67)
		)
		(stroke
			(width 0)
			(type default)
		)
	)
	(wire
		(pts
			(xy 209.55 133.35) (xy 224.79 133.35)
		)
		(stroke
			(width 0)
			(type default)
		)
	)
	(bus
		(pts
			(xy 171.45 148.59) (xy 171.45 156.21)
		)
		(stroke
			(width 0)
			(type default)
		)
	)
	(bus
		(pts
			(xy 168.91 163.83) (xy 171.45 161.29)
		)
		(stroke
			(width 0)
			(type default)
		)
	)
	(wire
		(pts
			(xy 240.03 130.81) (xy 240.03 133.35)
		)
		(stroke
			(width 0)
			(type default)
		)
	)
	(wire
		(pts
			(xy 198.12 193.04) (xy 195.58 193.04)
		)
		(stroke
			(width 0)
			(type default)
		)
	)
	(wire
		(pts
			(xy 173.99 156.21) (xy 203.2 156.21)
		)
		(stroke
			(width 0)
			(type default)
		)
	)
	(wire
		(pts
			(xy 195.58 193.04) (xy 195.58 195.58)
		)
		(stroke
			(width 0)
			(type default)
		)
	)
	(wire
		(pts
			(xy 196.85 148.59) (xy 203.2 148.59)
		)
		(stroke
			(width 0)
			(type default)
		)
	)
	(wire
		(pts
			(xy 196.85 133.35) (xy 209.55 133.35)
		)
		(stroke
			(width 0)
			(type default)
		)
	)
	(wire
		(pts
			(xy 182.88 190.5) (xy 198.12 190.5)
		)
		(stroke
			(width 0)
			(type default)
		)
	)
	(wire
		(pts
			(xy 224.79 158.75) (xy 224.79 156.21)
		)
		(stroke
			(width 0)
			(type default)
		)
	)
	(wire
		(pts
			(xy 173.99 146.05) (xy 203.2 146.05)
		)
		(stroke
			(width 0)
			(type default)
		)
	)
	(wire
		(pts
			(xy 246.38 187.96) (xy 229.87 187.96)
		)
		(stroke
			(width 0)
			(type default)
		)
	)
	(wire
		(pts
			(xy 182.88 185.42) (xy 198.12 185.42)
		)
		(stroke
			(width 0)
			(type default)
		)
	)
	(wire
		(pts
			(xy 224.79 143.51) (xy 224.79 147.32)
		)
		(stroke
			(width 0)
			(type default)
		)
	)
	(wire
		(pts
			(xy 193.04 133.35) (xy 196.85 133.35)
		)
		(stroke
			(width 0)
			(type default)
		)
	)
	(wire
		(pts
			(xy 193.04 133.35) (xy 193.04 135.89)
		)
		(stroke
			(width 0)
			(type default)
		)
	)
	(bus
		(pts
			(xy 171.45 148.59) (xy 171.45 146.05)
		)
		(stroke
			(width 0)
			(type default)
		)
	)
	(wire
		(pts
			(xy 224.79 143.51) (xy 222.25 143.51)
		)
		(stroke
			(width 0)
			(type default)
		)
	)
	(wire
		(pts
			(xy 232.41 195.58) (xy 232.41 185.42)
		)
		(stroke
			(width 0)
			(type default)
		)
	)
	(wire
		(pts
			(xy 195.58 187.96) (xy 195.58 193.04)
		)
		(stroke
			(width 0)
			(type default)
		)
	)
	(bus
		(pts
			(xy 171.45 156.21) (xy 171.45 158.75)
		)
		(stroke
			(width 0)
			(type default)
		)
	)
	(wire
		(pts
			(xy 227.33 133.35) (xy 224.79 133.35)
		)
		(stroke
			(width 0)
			(type default)
		)
	)
	(wire
		(pts
			(xy 246.38 193.04) (xy 229.87 193.04)
		)
		(stroke
			(width 0)
			(type default)
		)
	)
	(bus
		(pts
			(xy 168.91 163.83) (xy 166.37 163.83)
		)
		(stroke
			(width 0)
			(type default)
		)
	)
	(wire
		(pts
			(xy 196.85 135.89) (xy 196.85 133.35)
		)
		(stroke
			(width 0)
			(type default)
		)
	)
	(bus
		(pts
			(xy 171.45 158.75) (xy 171.45 161.29)
		)
		(stroke
			(width 0)
			(type default)
		)
	)
	(wire
		(pts
			(xy 193.04 140.97) (xy 193.04 151.13)
		)
		(stroke
			(width 0)
			(type default)
		)
	)
	(wire
		(pts
			(xy 182.88 182.88) (xy 198.12 182.88)
		)
		(stroke
			(width 0)
			(type default)
		)
	)
	(wire
		(pts
			(xy 240.03 133.35) (xy 232.41 133.35)
		)
		(stroke
			(width 0)
			(type default)
		)
	)
	(wire
		(pts
			(xy 198.12 187.96) (xy 195.58 187.96)
		)
		(stroke
			(width 0)
			(type default)
		)
	)
	(wire
		(pts
			(xy 193.04 151.13) (xy 203.2 151.13)
		)
		(stroke
			(width 0)
			(type default)
		)
	)
	(wire
		(pts
			(xy 224.79 156.21) (xy 222.25 156.21)
		)
		(stroke
			(width 0)
			(type default)
		)
	)
	(wire
		(pts
			(xy 224.79 152.4) (xy 224.79 156.21)
		)
		(stroke
			(width 0)
			(type default)
		)
	)
	(wire
		(pts
			(xy 224.79 133.35) (xy 224.79 143.51)
		)
		(stroke
			(width 0)
			(type default)
		)
	)
	(wire
		(pts
			(xy 232.41 185.42) (xy 229.87 185.42)
		)
		(stroke
			(width 0)
			(type default)
		)
	)
	(wire
		(pts
			(xy 173.99 143.51) (xy 203.2 143.51)
		)
		(stroke
			(width 0)
			(type default)
		)
	)
	(label "+3V3_FLASH"
		(at 182.88 182.88 0)
		(effects
			(font
				(size 1.27 1.27)
			)
			(justify left bottom)
		)
	)
	(label "FLASH.CLK"
		(at 175.26 153.67 0)
		(effects
			(font
				(size 1.27 1.27)
			)
			(justify left bottom)
		)
	)
	(label "FLASH.~{CE}"
		(at 182.88 185.42 0)
		(effects
			(font
				(size 1.27 1.27)
			)
			(justify left bottom)
		)
	)
	(label "~{HOLD}"
		(at 201.93 151.13 180)
		(effects
			(font
				(size 1.27 1.27)
			)
			(justify right bottom)
		)
	)
	(label "FLASH.MOSI"
		(at 175.26 143.51 0)
		(effects
			(font
				(size 1.27 1.27)
			)
			(justify left bottom)
		)
	)
	(label "FLASH.~{CE}"
		(at 175.26 156.21 0)
		(effects
			(font
				(size 1.27 1.27)
			)
			(justify left bottom)
		)
	)
	(label "+3V3_FLASH"
		(at 223.52 133.35 180)
		(effects
			(font
				(size 1.27 1.27)
			)
			(justify right bottom)
		)
	)
	(label "FLASH.MOSI"
		(at 246.38 187.96 180)
		(effects
			(font
				(size 1.27 1.27)
			)
			(justify right bottom)
		)
	)
	(label "FLASH.MISO"
		(at 175.26 146.05 0)
		(effects
			(font
				(size 1.27 1.27)
			)
			(justify left bottom)
		)
	)
	(label "FLASH.MISO"
		(at 246.38 193.04 180)
		(effects
			(font
				(size 1.27 1.27)
			)
			(justify right bottom)
		)
	)
	(label "FLASH.CLK"
		(at 182.88 190.5 0)
		(effects
			(font
				(size 1.27 1.27)
			)
			(justify left bottom)
		)
	)
	(label "~{WP}"
		(at 201.93 148.59 180)
		(effects
			(font
				(size 1.27 1.27)
			)
			(justify right bottom)
		)
	)
	(hierarchical_label "FLASH{SPI}"
		(shape bidirectional)
		(at 166.37 163.83 180)
		(effects
			(font
				(size 1.27 1.27)
			)
			(justify right)
		)
	)
	(symbol
		(lib_id "antmicropower:PWR_FLAG")
		(at 209.55 130.81 0)
		(unit 1)
		(exclude_from_sim no)
		(in_bom yes)
		(on_board yes)
		(dnp no)
		(property "Reference" "#FLG022"
			(at 209.55 128.905 0)
			(effects
				(font
					(size 1.27 1.27)
				)
				(hide yes)
			)
		)
		(property "Value" "PWR_FLAG"
			(at 209.55 127 0)
			(effects
				(font
					(size 1.27 1.27)
				)
			)
		)
		(property "Footprint" ""
			(at 209.55 130.81 0)
			(effects
				(font
					(size 1.27 1.27)
				)
				(hide yes)
			)
		)
		(property "Datasheet" ""
			(at 209.55 130.81 0)
			(effects
				(font
					(size 1.27 1.27)
				)
				(hide yes)
			)
		)
		(property "Description" ""
			(at 209.55 133.35 0)
			(effects
				(font
					(size 1.27 1.27)
				)
				(justify left bottom)
				(hide yes)
			)
		)
		(pin "1"
		)
		(instances
			(project ""
				(path ""
					(reference "#FLG022")
					(unit 1)
				)
			)
		)
	)
	(symbol
		(lib_id "antmicropower:GND")
		(at 195.58 195.58 0)
		(unit 1)
		(exclude_from_sim no)
		(in_bom yes)
		(on_board yes)
		(dnp no)
		(property "Reference" "#PWR0338"
			(at 204.47 198.12 0)
			(effects
				(font
					(size 1.27 1.27)
					(thickness 0.15)
				)
				(justify left bottom)
				(hide yes)
			)
		)
		(property "Value" "GND"
			(at 195.58 199.39 0)
			(effects
				(font
					(size 1.27 1.27)
					(thickness 0.15)
				)
			)
		)
		(property "Footprint" ""
			(at 204.47 203.2 0)
			(effects
				(font
					(size 1.27 1.27)
					(thickness 0.15)
				)
				(justify left bottom)
				(hide yes)
			)
		)
		(property "Datasheet" ""
			(at 204.47 208.28 0)
			(effects
				(font
					(size 1.27 1.27)
					(thickness 0.15)
				)
				(justify left bottom)
				(hide yes)
			)
		)
		(property "Description" ""
			(at 195.58 195.58 0)
			(effects
				(font
					(size 1.27 1.27)
				)
				(hide yes)
			)
		)
		(property "Author" "Antmicro"
			(at 204.47 203.2 0)
			(effects
				(font
					(size 1.27 1.27)
					(thickness 0.15)
				)
				(justify left bottom)
				(hide yes)
			)
		)
		(property "License" "Apache-2.0"
			(at 204.47 205.74 0)
			(effects
				(font
					(size 1.27 1.27)
					(thickness 0.15)
				)
				(justify left bottom)
				(hide yes)
			)
		)
		(pin "1"
		)
		(instances
			(project "OCuLink to 10GbE adapter"
				(path ""
					(reference "#PWR0338")
					(unit 1)
				)
			)
		)
	)
	(symbol
		(lib_id "antmicroDiodesRectifiersSingle:RB521S30T1G")
		(at 227.33 133.35 0)
		(mirror x)
		(unit 1)
		(exclude_from_sim no)
		(in_bom yes)
		(on_board yes)
		(dnp no)
		(fields_autoplaced yes)
		(property "Reference" "D12"
			(at 229.87 127 0)
			(effects
				(font
					(size 1.27 1.27)
					(thickness 0.15)
				)
			)
		)
		(property "Value" "RB521S30T1G"
			(at 250.19 118.11 0)
			(effects
				(font
					(size 1.27 1.27)
					(thickness 0.15)
				)
				(justify left bottom)
				(hide yes)
			)
		)
		(property "Footprint" "antmicro-footprints:SOD-523"
			(at 250.19 123.19 0)
			(effects
				(font
					(size 1.27 1.27)
					(thickness 0.15)
				)
				(justify left bottom)
				(hide yes)
			)
		)
		(property "Datasheet" "https://www.onsemi.com/pdf/datasheet/rb521s30t1-d.pdf"
			(at 250.19 120.65 0)
			(effects
				(font
					(size 1.27 1.27)
					(thickness 0.15)
				)
				(justify left bottom)
				(hide yes)
			)
		)
		(property "Description" "Small Signal Schottky Diode, Single, 30 V, 200 mA, 500 mV, 1 A, 125 °C"
			(at 250.19 107.95 0)
			(effects
				(font
					(size 1.27 1.27)
				)
				(justify left bottom)
				(hide yes)
			)
		)
		(property "MPN" "RB521S30T1G"
			(at 229.87 129.54 0)
			(effects
				(font
					(size 1.27 1.27)
					(thickness 0.15)
				)
			)
		)
		(property "Manufacturer" "ON Semiconductor"
			(at 250.19 115.57 0)
			(effects
				(font
					(size 1.27 1.27)
					(thickness 0.15)
				)
				(justify left bottom)
				(hide yes)
			)
		)
		(property "Author" "Antmicro"
			(at 250.19 113.03 0)
			(effects
				(font
					(size 1.27 1.27)
					(thickness 0.15)
				)
				(justify left bottom)
				(hide yes)
			)
		)
		(property "License" "Apache-2.0"
			(at 250.19 110.49 0)
			(effects
				(font
					(size 1.27 1.27)
					(thickness 0.15)
				)
				(justify left bottom)
				(hide yes)
			)
		)
		(pin "1"
		)
		(pin "2"
		)
		(instances
			(project "oculink-to-10gbe-adapter"
				(path ""
					(reference "D12")
					(unit 1)
				)
			)
		)
	)
	(symbol
		(lib_id "antmicroMemory:AT25DF641A-SH")
		(at 203.2 143.51 0)
		(unit 1)
		(exclude_from_sim no)
		(in_bom yes)
		(on_board yes)
		(dnp no)
		(fields_autoplaced yes)
		(property "Reference" "U13"
			(at 212.725 135.89 0)
			(effects
				(font
					(size 1.27 1.27)
					(thickness 0.15)
				)
			)
		)
		(property "Value" "AT25DF641A-SH"
			(at 236.22 151.13 0)
			(effects
				(font
					(size 1.27 1.27)
					(thickness 0.15)
				)
				(justify left bottom)
				(hide yes)
			)
		)
		(property "Footprint" "antmicro-footprints:SOIC-8_5.3x5.3x2mm_P1.27mm"
			(at 236.22 153.67 0)
			(effects
				(font
					(size 1.27 1.27)
					(thickness 0.15)
				)
				(justify left bottom)
				(hide yes)
			)
		)
		(property "Datasheet" "https://eu.mouser.com/datasheet/3/1166/1/REN_DS-AT25DF641A-8693G-022022_unsecure_DST_20220220_1.pdf"
			(at 236.22 156.21 0)
			(effects
				(font
					(size 1.27 1.27)
					(thickness 0.15)
				)
				(justify left bottom)
				(hide yes)
			)
		)
		(property "Description" "NOR Flash 64 Mbit, 3.0V (2.7V to 3.6V), -40C to 85C, SOIC-W 208mil (Tape & Reel), Single, Dual SPI NOR flash"
			(at 236.22 158.75 0)
			(effects
				(font
					(size 1.27 1.27)
					(thickness 0.15)
				)
				(justify left bottom)
				(hide yes)
			)
		)
		(property "MPN" "AT25DF641A-SH-T "
			(at 212.725 138.43 0)
			(effects
				(font
					(size 1.27 1.27)
					(thickness 0.15)
				)
			)
		)
		(property "Manufacturer" "Renesas"
			(at 236.22 161.29 0)
			(effects
				(font
					(size 1.27 1.27)
					(thickness 0.15)
				)
				(justify left bottom)
				(hide yes)
			)
		)
		(property "Author" "Antmicro"
			(at 236.22 163.83 0)
			(effects
				(font
					(size 1.27 1.27)
					(thickness 0.15)
				)
				(justify left bottom)
				(hide yes)
			)
		)
		(property "License" "Apache-2.0"
			(at 236.22 166.37 0)
			(effects
				(font
					(size 1.27 1.27)
					(thickness 0.15)
				)
				(justify left bottom)
				(hide yes)
			)
		)
		(pin "3"
		)
		(pin "5"
		)
		(pin "4"
		)
		(pin "7"
		)
		(pin "6"
		)
		(pin "2"
		)
		(pin "1"
		)
		(pin "8"
		)
		(instances
			(project ""
				(path ""
					(reference "U13")
					(unit 1)
				)
			)
		)
	)
	(symbol
		(lib_id "antmicroResistors0402:R_10k_0402")
		(at 193.04 140.97 270)
		(mirror x)
		(unit 1)
		(exclude_from_sim no)
		(in_bom yes)
		(on_board yes)
		(dnp no)
		(property "Reference" "R34"
			(at 191.77 137.16 90)
			(effects
				(font
					(size 1.27 1.27)
					(thickness 0.15)
				)
				(justify right)
			)
		)
		(property "Value" "R_10k_0402"
			(at 180.34 120.65 0)
			(effects
				(font
					(size 1.27 1.27)
					(thickness 0.15)
				)
				(justify left bottom)
				(hide yes)
			)
		)
		(property "Footprint" "antmicro-footprints:R_0402_1005Metric"
			(at 177.8 120.65 0)
			(effects
				(font
					(size 1.27 1.27)
					(thickness 0.15)
				)
				(justify left bottom)
				(hide yes)
			)
		)
		(property "Datasheet" "https://www.bourns.com/docs/product-datasheets/cr.pdf"
			(at 175.26 120.65 0)
			(effects
				(font
					(size 1.27 1.27)
					(thickness 0.15)
				)
				(justify left bottom)
				(hide yes)
			)
		)
		(property "Description" "SMD Chip Resistor, 10 kohm, ± 1%, 62.5 mW, 0402 [1005 Metric], Thick Film, General Purpose"
			(at 193.04 140.97 0)
			(effects
				(font
					(size 1.27 1.27)
				)
				(hide yes)
			)
		)
		(property "MPN" "CR0402-FX-1002GLF"
			(at 172.72 120.65 0)
			(effects
				(font
					(size 1.27 1.27)
					(thickness 0.15)
				)
				(justify left bottom)
				(hide yes)
			)
		)
		(property "Manufacturer" "Bourns"
			(at 170.18 120.65 0)
			(effects
				(font
					(size 1.27 1.27)
					(thickness 0.15)
				)
				(justify left bottom)
				(hide yes)
			)
		)
		(property "License" "Apache-2.0"
			(at 167.64 120.65 0)
			(effects
				(font
					(size 1.27 1.27)
					(thickness 0.15)
				)
				(justify left bottom)
				(hide yes)
			)
		)
		(property "Author" "Antmicro"
			(at 165.1 120.65 0)
			(effects
				(font
					(size 1.27 1.27)
					(thickness 0.15)
				)
				(justify left bottom)
				(hide yes)
			)
		)
		(property "Val" "10k"
			(at 191.77 139.7 90)
			(effects
				(font
					(size 1.27 1.27)
					(thickness 0.15)
				)
				(justify right)
			)
		)
		(property "Tolerance" "1%"
			(at 182.88 120.65 0)
			(effects
				(font
					(size 1.27 1.27)
				)
				(justify left bottom)
				(hide yes)
			)
		)
		(pin "1"
		)
		(pin "2"
		)
		(instances
			(project "OCuLink to 10GbE adapter"
				(path ""
					(reference "R34")
					(unit 1)
				)
			)
		)
	)
	(symbol
		(lib_id "antmicropower:GND")
		(at 232.41 195.58 0)
		(unit 1)
		(exclude_from_sim no)
		(in_bom yes)
		(on_board yes)
		(dnp no)
		(property "Reference" "#PWR0339"
			(at 241.3 198.12 0)
			(effects
				(font
					(size 1.27 1.27)
					(thickness 0.15)
				)
				(justify left bottom)
				(hide yes)
			)
		)
		(property "Value" "GND"
			(at 232.41 199.39 0)
			(effects
				(font
					(size 1.27 1.27)
					(thickness 0.15)
				)
			)
		)
		(property "Footprint" ""
			(at 241.3 203.2 0)
			(effects
				(font
					(size 1.27 1.27)
					(thickness 0.15)
				)
				(justify left bottom)
				(hide yes)
			)
		)
		(property "Datasheet" ""
			(at 241.3 208.28 0)
			(effects
				(font
					(size 1.27 1.27)
					(thickness 0.15)
				)
				(justify left bottom)
				(hide yes)
			)
		)
		(property "Description" ""
			(at 232.41 195.58 0)
			(effects
				(font
					(size 1.27 1.27)
				)
				(hide yes)
			)
		)
		(property "Author" "Antmicro"
			(at 241.3 203.2 0)
			(effects
				(font
					(size 1.27 1.27)
					(thickness 0.15)
				)
				(justify left bottom)
				(hide yes)
			)
		)
		(property "License" "Apache-2.0"
			(at 241.3 205.74 0)
			(effects
				(font
					(size 1.27 1.27)
					(thickness 0.15)
				)
				(justify left bottom)
				(hide yes)
			)
		)
		(pin "1"
		)
		(instances
			(project "OCuLink to 10GbE adapter"
				(path ""
					(reference "#PWR0339")
					(unit 1)
				)
			)
		)
	)
	(symbol
		(lib_id "antmicropower:+3V3")
		(at 240.03 130.81 0)
		(unit 1)
		(exclude_from_sim no)
		(in_bom yes)
		(on_board yes)
		(dnp no)
		(property "Reference" "#PWR064"
			(at 255.27 130.81 0)
			(effects
				(font
					(size 1.27 1.27)
					(thickness 0.15)
				)
				(justify left bottom)
				(hide yes)
			)
		)
		(property "Value" "+3V3"
			(at 240.03 127 0)
			(effects
				(font
					(size 1.27 1.27)
					(thickness 0.15)
				)
			)
		)
		(property "Footprint" ""
			(at 255.27 138.43 0)
			(effects
				(font
					(size 1.27 1.27)
					(thickness 0.15)
				)
				(justify left bottom)
				(hide yes)
			)
		)
		(property "Datasheet" ""
			(at 255.27 140.97 0)
			(effects
				(font
					(size 1.27 1.27)
					(thickness 0.15)
				)
				(justify left bottom)
				(hide yes)
			)
		)
		(property "Description" ""
			(at 240.03 130.81 0)
			(effects
				(font
					(size 1.27 1.27)
				)
				(hide yes)
			)
		)
		(property "Author" "Antmicro"
			(at 255.27 133.35 0)
			(effects
				(font
					(size 1.27 1.27)
					(thickness 0.15)
				)
				(justify left bottom)
				(hide yes)
			)
		)
		(property "License" "Apache-2.0"
			(at 255.27 135.89 0)
			(effects
				(font
					(size 1.27 1.27)
					(thickness 0.15)
				)
				(justify left bottom)
				(hide yes)
			)
		)
		(pin "1"
		)
		(instances
			(project "oculink-to-10gbe-adapter"
				(path ""
					(reference "#PWR064")
					(unit 1)
				)
			)
		)
	)
	(symbol
		(lib_id "antmicroCapacitors0402:C_100n_0402")
		(at 224.79 152.4 90)
		(unit 1)
		(exclude_from_sim no)
		(in_bom yes)
		(on_board yes)
		(dnp no)
		(fields_autoplaced yes)
		(property "Reference" "C47"
			(at 227.33 148.5836 90)
			(effects
				(font
					(size 1.27 1.27)
					(thickness 0.15)
				)
				(justify right)
			)
		)
		(property "Value" "C_100n_0402"
			(at 247.65 137.16 0)
			(effects
				(font
					(size 1.27 1.27)
					(thickness 0.15)
				)
				(justify left bottom)
				(hide yes)
			)
		)
		(property "Footprint" "antmicro-footprints:C_0402_1005Metric"
			(at 250.19 137.16 0)
			(effects
				(font
					(size 1.27 1.27)
					(thickness 0.15)
				)
				(justify left bottom)
				(hide yes)
			)
		)
		(property "Datasheet" "https://www.murata.com/products/productdetail?partno=GRM155R61H104KE14%23"
			(at 252.73 137.16 0)
			(effects
				(font
					(size 1.27 1.27)
					(thickness 0.15)
				)
				(justify left bottom)
				(hide yes)
			)
		)
		(property "Description" "SMD Multilayer Ceramic Capacitor, 0.1 µF, 50 V, 0402 [1005 Metric], ± 10%, X5R, GRM Series"
			(at 224.79 152.4 0)
			(effects
				(font
					(size 1.27 1.27)
				)
				(hide yes)
			)
		)
		(property "MPN" "GRM155R61H104KE14D"
			(at 255.27 137.16 0)
			(effects
				(font
					(size 1.27 1.27)
					(thickness 0.15)
				)
				(justify left bottom)
				(hide yes)
			)
		)
		(property "Val" "100n"
			(at 227.33 151.1236 90)
			(effects
				(font
					(size 1.27 1.27)
					(thickness 0.15)
				)
				(justify right)
			)
		)
		(property "Voltage" "50V"
			(at 234.95 137.16 0)
			(effects
				(font
					(size 1.27 1.27)
					(thickness 0.15)
				)
				(justify left bottom)
				(hide yes)
			)
		)
		(property "Dielectric" "X5R"
			(at 237.49 137.16 0)
			(effects
				(font
					(size 1.27 1.27)
					(thickness 0.15)
				)
				(justify left bottom)
				(hide yes)
			)
		)
		(property "Manufacturer" "Murata"
			(at 240.03 137.16 0)
			(effects
				(font
					(size 1.27 1.27)
					(thickness 0.15)
				)
				(justify left bottom)
				(hide yes)
			)
		)
		(property "License" "Apache-2.0"
			(at 242.57 137.16 0)
			(effects
				(font
					(size 1.27 1.27)
					(thickness 0.15)
				)
				(justify left bottom)
				(hide yes)
			)
		)
		(property "Author" "Antmicro"
			(at 245.11 137.16 0)
			(effects
				(font
					(size 1.27 1.27)
					(thickness 0.15)
				)
				(justify left bottom)
				(hide yes)
			)
		)
		(pin "2"
		)
		(pin "1"
		)
		(instances
			(project "OCuLink to 10GbE adapter"
				(path ""
					(reference "C47")
					(unit 1)
				)
			)
		)
	)
	(symbol
		(lib_id "antmicroResistors0402:R_10k_0402")
		(at 196.85 140.97 90)
		(unit 1)
		(exclude_from_sim no)
		(in_bom yes)
		(on_board yes)
		(dnp no)
		(property "Reference" "R35"
			(at 198.12 137.16 90)
			(effects
				(font
					(size 1.27 1.27)
					(thickness 0.15)
				)
				(justify right)
			)
		)
		(property "Value" "R_10k_0402"
			(at 209.55 120.65 0)
			(effects
				(font
					(size 1.27 1.27)
					(thickness 0.15)
				)
				(justify left bottom)
				(hide yes)
			)
		)
		(property "Footprint" "antmicro-footprints:R_0402_1005Metric"
			(at 212.09 120.65 0)
			(effects
				(font
					(size 1.27 1.27)
					(thickness 0.15)
				)
				(justify left bottom)
				(hide yes)
			)
		)
		(property "Datasheet" "https://www.bourns.com/docs/product-datasheets/cr.pdf"
			(at 214.63 120.65 0)
			(effects
				(font
					(size 1.27 1.27)
					(thickness 0.15)
				)
				(justify left bottom)
				(hide yes)
			)
		)
		(property "Description" "SMD Chip Resistor, 10 kohm, ± 1%, 62.5 mW, 0402 [1005 Metric], Thick Film, General Purpose"
			(at 196.85 140.97 0)
			(effects
				(font
					(size 1.27 1.27)
				)
				(hide yes)
			)
		)
		(property "MPN" "CR0402-FX-1002GLF"
			(at 217.17 120.65 0)
			(effects
				(font
					(size 1.27 1.27)
					(thickness 0.15)
				)
				(justify left bottom)
				(hide yes)
			)
		)
		(property "Manufacturer" "Bourns"
			(at 219.71 120.65 0)
			(effects
				(font
					(size 1.27 1.27)
					(thickness 0.15)
				)
				(justify left bottom)
				(hide yes)
			)
		)
		(property "License" "Apache-2.0"
			(at 222.25 120.65 0)
			(effects
				(font
					(size 1.27 1.27)
					(thickness 0.15)
				)
				(justify left bottom)
				(hide yes)
			)
		)
		(property "Author" "Antmicro"
			(at 224.79 120.65 0)
			(effects
				(font
					(size 1.27 1.27)
					(thickness 0.15)
				)
				(justify left bottom)
				(hide yes)
			)
		)
		(property "Val" "10k"
			(at 198.12 139.7 90)
			(effects
				(font
					(size 1.27 1.27)
					(thickness 0.15)
				)
				(justify right)
			)
		)
		(property "Tolerance" "1%"
			(at 207.01 120.65 0)
			(effects
				(font
					(size 1.27 1.27)
				)
				(justify left bottom)
				(hide yes)
			)
		)
		(pin "1"
		)
		(pin "2"
		)
		(instances
			(project ""
				(path ""
					(reference "R35")
					(unit 1)
				)
			)
		)
	)
	(symbol
		(lib_id "antmicroTestPoints:Tag-Connect_TC2050-IDC-NL_2x5_P1.27mm")
		(at 198.12 182.88 0)
		(unit 1)
		(exclude_from_sim no)
		(in_bom no)
		(on_board yes)
		(dnp yes)
		(property "Reference" "J10"
			(at 213.995 175.26 0)
			(effects
				(font
					(size 1.27 1.27)
					(thickness 0.15)
				)
			)
		)
		(property "Value" "Tag-Connect_TC2050-IDC-NL_2x5_P1.27mm"
			(at 237.49 186.69 0)
			(effects
				(font
					(size 1.27 1.27)
					(thickness 0.15)
				)
				(justify left bottom)
				(hide yes)
			)
		)
		(property "Footprint" "antmicro-footprints:Tag-Connect_TC2050-IDC-NL_2x5_P1.27mm"
			(at 237.49 189.23 0)
			(effects
				(font
					(size 1.27 1.27)
					(thickness 0.15)
				)
				(justify left bottom)
				(hide yes)
			)
		)
		(property "Datasheet" "https://www.tag-connect.com/wp-content/uploads/bsk-pdf-manager/TC2050-IDC-NL_Datasheet_8.pdf"
			(at 237.49 191.77 0)
			(effects
				(font
					(size 1.27 1.27)
					(thickness 0.15)
				)
				(justify left bottom)
				(hide yes)
			)
		)
		(property "Description" "Tag Connect 2x5 1.27mm terminal"
			(at 237.49 204.47 0)
			(effects
				(font
					(size 1.27 1.27)
				)
				(justify left bottom)
				(hide yes)
			)
		)
		(property "MPN" "TC2050-IDC-NL"
			(at 213.995 177.8 0)
			(effects
				(font
					(size 1.27 1.27)
					(thickness 0.15)
				)
			)
		)
		(property "Manufacturer" "Tag Connect"
			(at 237.49 196.85 0)
			(effects
				(font
					(size 1.27 1.27)
					(thickness 0.15)
				)
				(justify left bottom)
				(hide yes)
			)
		)
		(property "Author" "Antmicro"
			(at 237.49 199.39 0)
			(effects
				(font
					(size 1.27 1.27)
					(thickness 0.15)
				)
				(justify left bottom)
				(hide yes)
			)
		)
		(property "License" "Apache-2.0"
			(at 237.49 201.93 0)
			(effects
				(font
					(size 1.27 1.27)
					(thickness 0.15)
				)
				(justify left bottom)
				(hide yes)
			)
		)
		(pin "3"
			(alternate "GND")
		)
		(pin "5"
			(alternate "GND")
		)
		(pin "8"
			(alternate "SPI_MOSI")
		)
		(pin "7"
			(alternate "NC")
		)
		(pin "6"
			(alternate "SPI_MISO")
		)
		(pin "10"
			(alternate "SPI_NC")
		)
		(pin "4"
			(alternate "SPI_SCK")
		)
		(pin "2"
			(alternate "SPI_CS")
		)
		(pin "9"
			(alternate "GND")
		)
		(pin "1"
			(alternate "3V3")
		)
		(instances
			(project "oculink-to-10gbe-adapter"
				(path ""
					(reference "J10")
					(unit 1)
				)
			)
		)
	)
	(symbol
		(lib_id "antmicropower:GND")
		(at 224.79 158.75 0)
		(unit 1)
		(exclude_from_sim no)
		(in_bom yes)
		(on_board yes)
		(dnp no)
		(property "Reference" "#PWR065"
			(at 233.68 161.29 0)
			(effects
				(font
					(size 1.27 1.27)
					(thickness 0.15)
				)
				(justify left bottom)
				(hide yes)
			)
		)
		(property "Value" "GND"
			(at 224.79 162.56 0)
			(effects
				(font
					(size 1.27 1.27)
					(thickness 0.15)
				)
			)
		)
		(property "Footprint" ""
			(at 233.68 166.37 0)
			(effects
				(font
					(size 1.27 1.27)
					(thickness 0.15)
				)
				(justify left bottom)
				(hide yes)
			)
		)
		(property "Datasheet" ""
			(at 233.68 171.45 0)
			(effects
				(font
					(size 1.27 1.27)
					(thickness 0.15)
				)
				(justify left bottom)
				(hide yes)
			)
		)
		(property "Description" ""
			(at 224.79 158.75 0)
			(effects
				(font
					(size 1.27 1.27)
				)
				(hide yes)
			)
		)
		(property "Author" "Antmicro"
			(at 233.68 166.37 0)
			(effects
				(font
					(size 1.27 1.27)
					(thickness 0.15)
				)
				(justify left bottom)
				(hide yes)
			)
		)
		(property "License" "Apache-2.0"
			(at 233.68 168.91 0)
			(effects
				(font
					(size 1.27 1.27)
					(thickness 0.15)
				)
				(justify left bottom)
				(hide yes)
			)
		)
		(pin "1"
		)
		(instances
			(project "OCuLink to 10GbE adapter"
				(path ""
					(reference "#PWR065")
					(unit 1)
				)
			)
		)
	)
)
